(kicad_pcb
	(version 20260206)
	(generator "pcbnew")
	(generator_version "10.0")
	(general
		(thickness 1.6)
		(legacy_teardrops no)
	)
	(paper "A4")
	(title_block
		(title "01162023_DA0F0TEBIF0_F0T_Expander_BD_F_brd_V02_OCP.brd")
		(comment 1 "Grand Teton / footprints 4997-5004 of 9728")
	)
	(layers
		(0 "F.Cu" signal "TOP")
		(4 "In1.Cu" signal "GND")
		(6 "In2.Cu" signal "VCC")
		(8 "In3.Cu" signal "VCC1")
		(10 "In4.Cu" signal "GND1")
		(12 "In5.Cu" signal "IN1")
		(14 "In6.Cu" signal "GND2")
		(16 "In7.Cu" signal "IN2")
		(18 "In8.Cu" signal "GND3")
		(20 "In9.Cu" signal "IN3")
		(22 "In10.Cu" signal "GND4")
		(24 "In11.Cu" signal "IN4")
		(26 "In12.Cu" signal "GND5")
		(28 "In13.Cu" signal "IN5")
		(30 "In14.Cu" signal "GND6")
		(32 "In15.Cu" signal "IN6")
		(34 "In16.Cu" signal "GND7")
		(2 "B.Cu" signal "BOTTOM")
		(9 "F.Adhes" user "F.Adhesive")
		(11 "B.Adhes" user "B.Adhesive")
		(13 "F.Paste" user "Package Geometry/Pastemask Top")
		(15 "B.Paste" user "Package Geometry/Pastemask Bottom")
		(5 "F.SilkS" user "Ref Des/Silkscreen Top")
		(7 "B.SilkS" user "Ref Des/Silkscreen Bottom")
		(1 "F.Mask" user "Board Geometry/Soldermask Top")
		(3 "B.Mask" user "Board Geometry/Soldermask Bottom")
		(17 "Dwgs.User" user "User.Drawings")
		(19 "Cmts.User" user "User.Comments")
		(21 "Eco1.User" user "User.Eco1")
		(23 "Eco2.User" user "User.Eco2")
		(25 "Edge.Cuts" user "Board Geometry/Outline")
		(27 "Margin" user)
		(31 "F.CrtYd" user "Package Geometry/Place Bound Top")
		(29 "B.CrtYd" user "Package Geometry/Place Bound Bottom")
		(35 "F.Fab" user "Ref Des/Assembly Top")
		(33 "B.Fab" user "Ref Des/Assembly Bottom")
	)
	(footprint ""
		(layer "F.Cu")
		(at 104.517698 -380.123446 90)
		(property "Reference" "R6732"
			(at 0 0 90)
			(layer "F.SilkS")
			(hide yes)
			(effects
				(font
					(size 1.27 1.27)
				)
			)
		)
		(property "Value" ""
			(at 0 0 90)
			(layer "F.Fab")
			(effects
				(font
					(size 1.27 1.27)
				)
			)
		)
		(duplicate_pad_numbers_are_jumpers no)
		(fp_line
			(start 0.7874 -0.4064)
			(end 0.7874 0.4064)
			(stroke
				(width 0.1524)
				(type default)
			)
			(layer "F.SilkS")
		)
		(fp_line
			(start -0.7874 -0.4064)
			(end 0.7874 -0.4064)
			(stroke
				(width 0.1524)
				(type default)
			)
			(layer "F.SilkS")
		)
		(fp_line
			(start 0.02032 0.4064)
			(end -0.7874 0.4064)
			(stroke
				(width 0.1524)
				(type default)
			)
			(layer "F.SilkS")
		)
		(fp_line
			(start -0.12065 -0.305054)
			(end -0.12065 -0.2794)
			(stroke
				(width 0.1)
				(type default)
			)
			(layer "F.Fab")
		)
		(fp_line
			(start -0.67945 -0.305054)
			(end -0.12065 -0.305054)
			(stroke
				(width 0.1)
				(type default)
			)
			(layer "F.Fab")
		)
		(fp_line
			(start 0.67945 -0.3048)
			(end 0.67945 0.3048)
			(stroke
				(width 0.1)
				(type default)
			)
			(layer "F.Fab")
		)
		(fp_line
			(start 0.12065 -0.3048)
			(end 0.67945 -0.3048)
			(stroke
				(width 0.1)
				(type default)
			)
			(layer "F.Fab")
		)
		(fp_line
			(start 0.12065 -0.2794)
			(end 0.12065 -0.3048)
			(stroke
				(width 0.1)
				(type default)
			)
			(layer "F.Fab")
		)
		(fp_line
			(start -0.12065 -0.2794)
			(end 0.12065 -0.2794)
			(stroke
				(width 0.1)
				(type default)
			)
			(layer "F.Fab")
		)
		(fp_line
			(start 0.120396 0.2794)
			(end -0.12065 0.2794)
			(stroke
				(width 0.1)
				(type default)
			)
			(layer "F.Fab")
		)
		(fp_line
			(start -0.12065 0.2794)
			(end -0.12065 0.3048)
			(stroke
				(width 0.1)
				(type default)
			)
			(layer "F.Fab")
		)
		(fp_line
			(start 0.67945 0.3048)
			(end 0.120396 0.3048)
			(stroke
				(width 0.1)
				(type default)
			)
			(layer "F.Fab")
		)
		(fp_line
			(start 0.120396 0.3048)
			(end 0.120396 0.2794)
			(stroke
				(width 0.1)
				(type default)
			)
			(layer "F.Fab")
		)
		(fp_line
			(start -0.12065 0.3048)
			(end -0.67945 0.3048)
			(stroke
				(width 0.1)
				(type default)
			)
			(layer "F.Fab")
		)
		(fp_line
			(start -0.67945 0.3048)
			(end -0.67945 -0.305054)
			(stroke
				(width 0.1)
				(type default)
			)
			(layer "F.Fab")
		)
		(pad "1" smd rect
			(at -0.40005 0 270)
			(size 0.4572 0.508)
			(layers "F.Cu" "F.Mask" "F.Paste")
			(net "USB2_BIC_USB8042_DN")
		)
		(pad "2" smd rect
			(at 0.40005 0 270)
			(size 0.4572 0.508)
			(layers "F.Cu" "F.Mask" "F.Paste")
			(net "USB2_BIC_DN")
		)
	)
	(footprint ""
		(layer "F.Cu")
		(at 224.856294 -183.58358)
		(property "Reference" "R5495"
			(at 0 0 0)
			(layer "F.SilkS")
			(hide yes)
			(effects
				(font
					(size 1.27 1.27)
				)
			)
		)
		(property "Value" ""
			(at 0 0 0)
			(layer "F.Fab")
			(effects
				(font
					(size 1.27 1.27)
				)
			)
		)
		(duplicate_pad_numbers_are_jumpers no)
		(fp_line
			(start -0.7874 -0.4064)
			(end 0.7874 -0.4064)
			(stroke
				(width 0.1524)
				(type default)
			)
			(layer "F.SilkS")
		)
		(fp_line
			(start -0.7874 0.4064)
			(end -0.7874 -0.4064)
			(stroke
				(width 0.1524)
				(type default)
			)
			(layer "F.SilkS")
		)
		(fp_line
			(start 0.7874 -0.4064)
			(end 0.7874 0.4064)
			(stroke
				(width 0.1524)
				(type default)
			)
			(layer "F.SilkS")
		)
		(fp_line
			(start 0.7874 0.4064)
			(end -0.7874 0.4064)
			(stroke
				(width 0.1524)
				(type default)
			)
			(layer "F.SilkS")
		)
		(fp_line
			(start -0.67945 -0.305054)
			(end -0.12065 -0.305054)
			(stroke
				(width 0.1)
				(type default)
			)
			(layer "F.Fab")
		)
		(fp_line
			(start -0.67945 0.3048)
			(end -0.67945 -0.305054)
			(stroke
				(width 0.1)
				(type default)
			)
			(layer "F.Fab")
		)
		(fp_line
			(start -0.12065 -0.305054)
			(end -0.12065 -0.2794)
			(stroke
				(width 0.1)
				(type default)
			)
			(layer "F.Fab")
		)
		(fp_line
			(start -0.12065 -0.2794)
			(end 0.12065 -0.2794)
			(stroke
				(width 0.1)
				(type default)
			)
			(layer "F.Fab")
		)
		(fp_line
			(start -0.12065 0.2794)
			(end -0.12065 0.3048)
			(stroke
				(width 0.1)
				(type default)
			)
			(layer "F.Fab")
		)
		(fp_line
			(start -0.12065 0.3048)
			(end -0.67945 0.3048)
			(stroke
				(width 0.1)
				(type default)
			)
			(layer "F.Fab")
		)
		(fp_line
			(start 0.120396 0.2794)
			(end -0.12065 0.2794)
			(stroke
				(width 0.1)
				(type default)
			)
			(layer "F.Fab")
		)
		(fp_line
			(start 0.120396 0.3048)
			(end 0.120396 0.2794)
			(stroke
				(width 0.1)
				(type default)
			)
			(layer "F.Fab")
		)
		(fp_line
			(start 0.12065 -0.3048)
			(end 0.67945 -0.3048)
			(stroke
				(width 0.1)
				(type default)
			)
			(layer "F.Fab")
		)
		(fp_line
			(start 0.12065 -0.2794)
			(end 0.12065 -0.3048)
			(stroke
				(width 0.1)
				(type default)
			)
			(layer "F.Fab")
		)
		(fp_line
			(start 0.67945 -0.3048)
			(end 0.67945 0.3048)
			(stroke
				(width 0.1)
				(type default)
			)
			(layer "F.Fab")
		)
		(fp_line
			(start 0.67945 0.3048)
			(end 0.120396 0.3048)
			(stroke
				(width 0.1)
				(type default)
			)
			(layer "F.Fab")
		)
		(pad "1" smd circle
			(at -0.40005 0)
			(size 0 0)
			(layers "F.Cu" "F.Mask" "F.Paste")
			(net "RST_BIC_BUF_RSMRST_N_BUF")
		)
		(pad "2" smd circle
			(at 0.40005 0)
			(size 0 0)
			(layers "F.Cu" "F.Mask" "F.Paste")
			(net "RST_BJT_Q15_B")
		)
	)
	(footprint ""
		(layer "F.Cu")
		(at 236.887512 -231.416606 90)
		(property "Reference" "R4520"
			(at 0 0 90)
			(layer "F.SilkS")
			(hide yes)
			(effects
				(font
					(size 1.27 1.27)
				)
			)
		)
		(property "Value" ""
			(at 0 0 90)
			(layer "F.Fab")
			(effects
				(font
					(size 1.27 1.27)
				)
			)
		)
		(duplicate_pad_numbers_are_jumpers no)
		(fp_line
			(start 0.7874 -0.4064)
			(end 0.7874 0.4064)
			(stroke
				(width 0.1524)
				(type default)
			)
			(layer "F.SilkS")
		)
		(fp_line
			(start -0.7874 -0.4064)
			(end 0.7874 -0.4064)
			(stroke
				(width 0.1524)
				(type default)
			)
			(layer "F.SilkS")
		)
		(fp_line
			(start 0.7874 0.4064)
			(end -0.7874 0.4064)
			(stroke
				(width 0.1524)
				(type default)
			)
			(layer "F.SilkS")
		)
		(fp_line
			(start -0.7874 0.4064)
			(end -0.7874 -0.4064)
			(stroke
				(width 0.1524)
				(type default)
			)
			(layer "F.SilkS")
		)
		(fp_line
			(start -0.12065 -0.305054)
			(end -0.12065 -0.2794)
			(stroke
				(width 0.1)
				(type default)
			)
			(layer "F.Fab")
		)
		(fp_line
			(start -0.67945 -0.305054)
			(end -0.12065 -0.305054)
			(stroke
				(width 0.1)
				(type default)
			)
			(layer "F.Fab")
		)
		(fp_line
			(start 0.67945 -0.3048)
			(end 0.67945 0.3048)
			(stroke
				(width 0.1)
				(type default)
			)
			(layer "F.Fab")
		)
		(fp_line
			(start 0.12065 -0.3048)
			(end 0.67945 -0.3048)
			(stroke
				(width 0.1)
				(type default)
			)
			(layer "F.Fab")
		)
		(fp_line
			(start 0.12065 -0.2794)
			(end 0.12065 -0.3048)
			(stroke
				(width 0.1)
				(type default)
			)
			(layer "F.Fab")
		)
		(fp_line
			(start -0.12065 -0.2794)
			(end 0.12065 -0.2794)
			(stroke
				(width 0.1)
				(type default)
			)
			(layer "F.Fab")
		)
		(fp_line
			(start 0.120396 0.2794)
			(end -0.12065 0.2794)
			(stroke
				(width 0.1)
				(type default)
			)
			(layer "F.Fab")
		)
		(fp_line
			(start -0.12065 0.2794)
			(end -0.12065 0.3048)
			(stroke
				(width 0.1)
				(type default)
			)
			(layer "F.Fab")
		)
		(fp_line
			(start 0.67945 0.3048)
			(end 0.120396 0.3048)
			(stroke
				(width 0.1)
				(type default)
			)
			(layer "F.Fab")
		)
		(fp_line
			(start 0.120396 0.3048)
			(end 0.120396 0.2794)
			(stroke
				(width 0.1)
				(type default)
			)
			(layer "F.Fab")
		)
		(fp_line
			(start -0.12065 0.3048)
			(end -0.67945 0.3048)
			(stroke
				(width 0.1)
				(type default)
			)
			(layer "F.Fab")
		)
		(fp_line
			(start -0.67945 0.3048)
			(end -0.67945 -0.305054)
			(stroke
				(width 0.1)
				(type default)
			)
			(layer "F.Fab")
		)
		(pad "1" smd circle
			(at -0.40005 0 90)
			(size 0 0)
			(layers "F.Cu" "F.Mask" "F.Paste")
			(net "SSD6_PWRDIS_BIC")
		)
		(pad "2" smd circle
			(at 0.40005 0 90)
			(size 0 0)
			(layers "F.Cu" "F.Mask" "F.Paste")
			(net "SSD6_PWRDIS_BIC_R")
		)
	)
	(footprint ""
		(layer "F.Cu")
		(at 80.019398 -122.270266 180)
		(property "Reference" "C28"
			(at 0 0 180)
			(layer "F.SilkS")
			(hide yes)
			(effects
				(font
					(size 1.27 1.27)
				)
			)
		)
		(property "Value" ""
			(at 0 0 180)
			(layer "F.Fab")
			(effects
				(font
					(size 1.27 1.27)
				)
			)
		)
		(duplicate_pad_numbers_are_jumpers no)
		(fp_line
			(start 0.299974 0.150114)
			(end -0.299974 0.150114)
			(stroke
				(width 0.1)
				(type default)
			)
			(layer "F.Fab")
		)
		(fp_line
			(start 0.299974 -0.150114)
			(end 0.299974 0.150114)
			(stroke
				(width 0.1)
				(type default)
			)
			(layer "F.Fab")
		)
		(fp_line
			(start -0.299974 0.150114)
			(end -0.299974 -0.150114)
			(stroke
				(width 0.1)
				(type default)
			)
			(layer "F.Fab")
		)
		(fp_line
			(start -0.299974 -0.150114)
			(end 0.299974 -0.150114)
			(stroke
				(width 0.1)
				(type default)
			)
			(layer "F.Fab")
		)
		(pad "1" smd rect
			(at -0.2667 0 180)
			(size 0.3048 0.381)
			(layers "F.Cu" "F.Mask" "F.Paste")
			(net "P5E_PEX0_STN0_TX_DN<2>")
		)
		(pad "2" smd rect
			(at 0.2667 0 180)
			(size 0.3048 0.381)
			(layers "F.Cu" "F.Mask" "F.Paste")
			(net "P5E_PEX0_STN0_TX_C_DN<2>")
		)
	)
	(footprint ""
		(layer "F.Cu")
		(at 314.726574 -53.697124 -90)
		(property "Reference" "PC546"
			(at 0 0 270)
			(layer "F.SilkS")
			(hide yes)
			(effects
				(font
					(size 1.27 1.27)
				)
			)
		)
		(property "Value" ""
			(at 0 0 270)
			(layer "F.Fab")
			(effects
				(font
					(size 1.27 1.27)
				)
			)
		)
		(duplicate_pad_numbers_are_jumpers no)
		(fp_line
			(start -0.7874 0.4064)
			(end -0.7874 -0.4064)
			(stroke
				(width 0.1524)
				(type default)
			)
			(layer "F.SilkS")
		)
		(fp_line
			(start 0.7874 0.4064)
			(end -0.7874 0.4064)
			(stroke
				(width 0.1524)
				(type default)
			)
			(layer "F.SilkS")
		)
		(fp_line
			(start -0.7874 -0.4064)
			(end 0.7874 -0.4064)
			(stroke
				(width 0.1524)
				(type default)
			)
			(layer "F.SilkS")
		)
		(fp_line
			(start 0.7874 -0.4064)
			(end 0.7874 0.4064)
			(stroke
				(width 0.1524)
				(type default)
			)
			(layer "F.SilkS")
		)
		(fp_line
			(start -0.67945 0.3048)
			(end -0.67945 -0.305054)
			(stroke
				(width 0.1)
				(type default)
			)
			(layer "F.Fab")
		)
		(fp_line
			(start -0.12065 0.3048)
			(end -0.67945 0.3048)
			(stroke
				(width 0.1)
				(type default)
			)
			(layer "F.Fab")
		)
		(fp_line
			(start 0.120396 0.3048)
			(end 0.120396 0.2794)
			(stroke
				(width 0.1)
				(type default)
			)
			(layer "F.Fab")
		)
		(fp_line
			(start 0.67945 0.3048)
			(end 0.120396 0.3048)
			(stroke
				(width 0.1)
				(type default)
			)
			(layer "F.Fab")
		)
		(fp_line
			(start -0.12065 0.2794)
			(end -0.12065 0.3048)
			(stroke
				(width 0.1)
				(type default)
			)
			(layer "F.Fab")
		)
		(fp_line
			(start 0.120396 0.2794)
			(end -0.12065 0.2794)
			(stroke
				(width 0.1)
				(type default)
			)
			(layer "F.Fab")
		)
		(fp_line
			(start -0.12065 -0.2794)
			(end 0.12065 -0.2794)
			(stroke
				(width 0.1)
				(type default)
			)
			(layer "F.Fab")
		)
		(fp_line
			(start 0.12065 -0.2794)
			(end 0.12065 -0.3048)
			(stroke
				(width 0.1)
				(type default)
			)
			(layer "F.Fab")
		)
		(fp_line
			(start 0.12065 -0.3048)
			(end 0.67945 -0.3048)
			(stroke
				(width 0.1)
				(type default)
			)
			(layer "F.Fab")
		)
		(fp_line
			(start 0.67945 -0.3048)
			(end 0.67945 0.3048)
			(stroke
				(width 0.1)
				(type default)
			)
			(layer "F.Fab")
		)
		(fp_line
			(start -0.67945 -0.305054)
			(end -0.12065 -0.305054)
			(stroke
				(width 0.1)
				(type default)
			)
			(layer "F.Fab")
		)
		(fp_line
			(start -0.12065 -0.305054)
			(end -0.12065 -0.2794)
			(stroke
				(width 0.1)
				(type default)
			)
			(layer "F.Fab")
		)
		(pad "1" smd circle
			(at -0.40005 0 270)
			(size 0 0)
			(layers "F.Cu" "F.Mask" "F.Paste")
			(net "P3V3_AUX")
		)
		(pad "2" smd circle
			(at 0.40005 0 270)
			(size 0 0)
			(layers "F.Cu" "F.Mask" "F.Paste")
			(net "GND")
		)
	)
	(footprint ""
		(layer "F.Cu")
		(at 270.980662 -343.952322 90)
		(property "Reference" "C611"
			(at 0 0 90)
			(layer "F.SilkS")
			(hide yes)
			(effects
				(font
					(size 1.27 1.27)
				)
			)
		)
		(property "Value" ""
			(at 0 0 90)
			(layer "F.Fab")
			(effects
				(font
					(size 1.27 1.27)
				)
			)
		)
		(duplicate_pad_numbers_are_jumpers no)
		(fp_line
			(start 0.299974 -0.150114)
			(end 0.299974 0.150114)
			(stroke
				(width 0.1)
				(type default)
			)
			(layer "F.Fab")
		)
		(fp_line
			(start -0.299974 -0.150114)
			(end 0.299974 -0.150114)
			(stroke
				(width 0.1)
				(type default)
			)
			(layer "F.Fab")
		)
		(fp_line
			(start 0.299974 0.150114)
			(end -0.299974 0.150114)
			(stroke
				(width 0.1)
				(type default)
			)
			(layer "F.Fab")
		)
		(fp_line
			(start -0.299974 0.150114)
			(end -0.299974 -0.150114)
			(stroke
				(width 0.1)
				(type default)
			)
			(layer "F.Fab")
		)
		(pad "1" smd rect
			(at -0.2667 0 90)
			(size 0.3048 0.381)
			(layers "F.Cu" "F.Mask" "F.Paste")
			(net "P5E_PEX2_STN7_TX_DP<113>")
		)
		(pad "2" smd rect
			(at 0.2667 0 90)
			(size 0.3048 0.381)
			(layers "F.Cu" "F.Mask" "F.Paste")
			(net "P5E_PEX2_STN7_TX_C_DP<113>")
		)
	)
	(footprint ""
		(layer "F.Cu")
		(at 227.708714 -117.698012 90)
		(property "Reference" "PR6887"
			(at 0 0 90)
			(layer "F.SilkS")
			(hide yes)
			(effects
				(font
					(size 1.27 1.27)
				)
			)
		)
		(property "Value" ""
			(at 0 0 90)
			(layer "F.Fab")
			(effects
				(font
					(size 1.27 1.27)
				)
			)
		)
		(duplicate_pad_numbers_are_jumpers no)
		(fp_line
			(start 0.7874 -0.4064)
			(end 0.7874 0.4064)
			(stroke
				(width 0.1524)
				(type default)
			)
			(layer "F.SilkS")
		)
		(fp_line
			(start -0.7874 -0.4064)
			(end 0.7874 -0.4064)
			(stroke
				(width 0.1524)
				(type default)
			)
			(layer "F.SilkS")
		)
		(fp_line
			(start 0.7874 0.4064)
			(end -0.7874 0.4064)
			(stroke
				(width 0.1524)
				(type default)
			)
			(layer "F.SilkS")
		)
		(fp_line
			(start -0.7874 0.4064)
			(end -0.7874 -0.4064)
			(stroke
				(width 0.1524)
				(type default)
			)
			(layer "F.SilkS")
		)
		(fp_line
			(start -0.12065 -0.305054)
			(end -0.12065 -0.2794)
			(stroke
				(width 0.1)
				(type default)
			)
			(layer "F.Fab")
		)
		(fp_line
			(start -0.67945 -0.305054)
			(end -0.12065 -0.305054)
			(stroke
				(width 0.1)
				(type default)
			)
			(layer "F.Fab")
		)
		(fp_line
			(start 0.67945 -0.3048)
			(end 0.67945 0.3048)
			(stroke
				(width 0.1)
				(type default)
			)
			(layer "F.Fab")
		)
		(fp_line
			(start 0.12065 -0.3048)
			(end 0.67945 -0.3048)
			(stroke
				(width 0.1)
				(type default)
			)
			(layer "F.Fab")
		)
		(fp_line
			(start 0.12065 -0.2794)
			(end 0.12065 -0.3048)
			(stroke
				(width 0.1)
				(type default)
			)
			(layer "F.Fab")
		)
		(fp_line
			(start -0.12065 -0.2794)
			(end 0.12065 -0.2794)
			(stroke
				(width 0.1)
				(type default)
			)
			(layer "F.Fab")
		)
		(fp_line
			(start 0.120396 0.2794)
			(end -0.12065 0.2794)
			(stroke
				(width 0.1)
				(type default)
			)
			(layer "F.Fab")
		)
		(fp_line
			(start -0.12065 0.2794)
			(end -0.12065 0.3048)
			(stroke
				(width 0.1)
				(type default)
			)
			(layer "F.Fab")
		)
		(fp_line
			(start 0.67945 0.3048)
			(end 0.120396 0.3048)
			(stroke
				(width 0.1)
				(type default)
			)
			(layer "F.Fab")
		)
		(fp_line
			(start 0.120396 0.3048)
			(end 0.120396 0.2794)
			(stroke
				(width 0.1)
				(type default)
			)
			(layer "F.Fab")
		)
		(fp_line
			(start -0.12065 0.3048)
			(end -0.67945 0.3048)
			(stroke
				(width 0.1)
				(type default)
			)
			(layer "F.Fab")
		)
		(fp_line
			(start -0.67945 0.3048)
			(end -0.67945 -0.305054)
			(stroke
				(width 0.1)
				(type default)
			)
			(layer "F.Fab")
		)
		(pad "1" smd circle
			(at -0.40005 0 90)
			(size 0 0)
			(layers "F.Cu" "F.Mask" "F.Paste")
			(net "P12V_NIC3_R")
		)
		(pad "2" smd circle
			(at 0.40005 0 90)
			(size 0 0)
			(layers "F.Cu" "F.Mask" "F.Paste")
			(net "P12V_NIC3_CO_AVIN_PD")
		)
	)
	(footprint ""
		(layer "F.Cu")
		(at 461.600042 -398.100042)
		(property "Reference" "H75"
			(at -3.578606 -2.749042 0)
			(unlocked yes)
			(layer "F.SilkS")
			(effects
				(font
					(size 0.7874 0.5842)
					(thickness 0.1524)
				)
				(justify left)
			)
		)
		(property "Value" ""
			(at 0 0 0)
			(layer "F.Fab")
			(effects
				(font
					(size 1.27 1.27)
				)
			)
		)
		(duplicate_pad_numbers_are_jumpers no)
		(fp_circle
			(center 0 0)
			(end 2.6289 0)
			(stroke
				(width 0.1524)
				(type default)
			)
			(fill no)
			(layer "F.SilkS")
		)
		(fp_circle
			(center 0 0)
			(end 2.6289 0)
			(stroke
				(width 0.1524)
				(type default)
			)
			(fill no)
			(layer "B.SilkS")
		)
		(fp_circle
			(center 0 0)
			(end 2.6289 0)
			(stroke
				(width 0.1)
				(type default)
			)
			(fill no)
			(layer "B.Fab")
		)
		(fp_circle
			(center 0 0)
			(end 2.6289 0)
			(stroke
				(width 0.1)
				(type default)
			)
			(fill no)
			(layer "F.Fab")
		)
		(pad "" np_thru_hole circle
			(at 0 0)
			(size 3.0988 3.0988)
			(drill 3.0988)
			(layers "*.Cu" "*.Mask")
			(clearance 0.254)
			(thermal_gap 0.254)
		)
		(zone
			(layers "F.Cu" "B.Cu" "In1.Cu" "In2.Cu" "In3.Cu" "In4.Cu" "In5.Cu" "In6.Cu"
				"In7.Cu" "In8.Cu" "In9.Cu" "In10.Cu" "In11.Cu" "In12.Cu" "In13.Cu" "In14.Cu"
				"In15.Cu" "In16.Cu"
			)
			(hatch none 0.5)
			(connect_pads
				(clearance 0)
			)
			(min_thickness 0.25)
			(keepout
				(tracks not_allowed)
				(vias allowed)
				(pads allowed)
				(copperpour not_allowed)
				(footprints allowed)
			)
			(placement
				(enabled no)
				(sheetname "")
			)
			(fill
				(thermal_gap 0.5)
				(thermal_bridge_width 0.5)
				(island_removal_mode 0)
			)
			(polygon
				(pts
					(arc
						(start 463.657442 -398.100042)
						(mid 459.542642 -398.100042)
						(end 463.657442 -398.100042)
					)
				)
			)
		)
	)
)
